# BASEBOARD_FAB2 (Tioga Pass) — schematic netlist excerpt (pin names and nets, part order shuffled) for the footprints in the layout excerpt that follows; sources: Cadence DE-HDL packaged netlist, KiCad conversion of Wiwynn_Tioga_Pass_MB.brd

R7U2  RES  100.0 1% EMPTY  pkg 0402  page 225 : A = VSENSE_PVDDQ_GHJ_P ; B = VSENSE_PVDDQ_GHJ_N
R6T3  RES  10.0 1% CHIP  pkg 0402  page 99 : A = SMB_DDR_GHJ_SCL_G_R ; B = SMB_DDR_GHJ_SCL_G
C4P4  CAP  100UF 4V 20% X5R  pkg 0805  page 42 : A = PVCCMCP_CPU0 ; B = GND

(kicad_pcb
	(version 20260206)
	(generator "pcbnew")
	(generator_version "10.0")
	(general
		(thickness 1.6)
		(legacy_teardrops no)
	)
	(paper "A4")
	(title_block
		(title "Wiwynn_Tioga_Pass_MB.brd")
		(comment 1 "Tioga Pass / footprints 4589-4591 of 4770")
	)
	(layers
		(0 "F.Cu" signal "TOP")
		(4 "In1.Cu" signal "L2GND")
		(6 "In2.Cu" signal "L3")
		(8 "In3.Cu" signal "L4GND")
		(10 "In4.Cu" signal "L5")
		(12 "In5.Cu" signal "L6GND")
		(14 "In6.Cu" signal "L7VCC")
		(16 "In7.Cu" signal "L8VCC")
		(18 "In8.Cu" signal "L9GND")
		(20 "In9.Cu" signal "L10")
		(22 "In10.Cu" signal "L11GND")
		(24 "In11.Cu" signal "L12")
		(26 "In12.Cu" signal "L13GND")
		(2 "B.Cu" signal "BOTTOM")
		(9 "F.Adhes" user "F.Adhesive")
		(11 "B.Adhes" user "B.Adhesive")
		(13 "F.Paste" user "Package Geometry/Pastemask Top")
		(15 "B.Paste" user "Package Geometry/Pastemask Bottom")
		(5 "F.SilkS" user "Ref Des/Silkscreen Top")
		(7 "B.SilkS" user "Ref Des/Silkscreen Bottom")
		(1 "F.Mask" user "Board Geometry/Soldermask Top")
		(3 "B.Mask" user "Board Geometry/Soldermask Bottom")
		(17 "Dwgs.User" user "User.Drawings")
		(19 "Cmts.User" user "User.Comments")
		(21 "Eco1.User" user "User.Eco1")
		(23 "Eco2.User" user "User.Eco2")
		(25 "Edge.Cuts" user "Board Geometry/Outline")
		(27 "Margin" user)
		(31 "F.CrtYd" user "Package Geometry/Place Bound Top")
		(29 "B.CrtYd" user "Package Geometry/Place Bound Bottom")
		(35 "F.Fab" user "Ref Des/Assembly Top")
		(33 "B.Fab" user "Ref Des/Assembly Bottom")
	)
	(footprint ""
		(layer "B.Cu")
		(at 167.61587 -22.749764 -90)
		(property "Reference" "R6T3"
			(at 0 0 90)
			(layer "B.SilkS")
			(hide yes)
			(effects
				(font
					(size 1.27 1.27)
				)
				(justify mirror)
			)
		)
		(property "Value" ""
			(at 0 0 90)
			(layer "B.Fab")
			(effects
				(font
					(size 1.27 1.27)
				)
				(justify mirror)
			)
		)
		(duplicate_pad_numbers_are_jumpers no)
		(fp_poly
			(pts
				(xy 0.2794 -0.101854) (xy -0.2794 -0.101854) (xy -0.2794 0.990346) (xy 0.2794 0.990346)
			)
			(stroke
				(width 0)
				(type default)
			)
			(fill no)
			(layer "B.CrtYd")
		)
		(fp_line
			(start -0.2794 0.990346)
			(end -0.2794 -0.101854)
			(stroke
				(width 0.1)
				(type default)
			)
			(layer "B.Fab")
		)
		(fp_line
			(start 0.2794 0.990346)
			(end -0.2794 0.990346)
			(stroke
				(width 0.1)
				(type default)
			)
			(layer "B.Fab")
		)
		(fp_line
			(start -0.2794 -0.101854)
			(end 0.2794 -0.101854)
			(stroke
				(width 0.1)
				(type default)
			)
			(layer "B.Fab")
		)
		(fp_line
			(start 0.2794 -0.101854)
			(end 0.2794 0.990346)
			(stroke
				(width 0.1)
				(type default)
			)
			(layer "B.Fab")
		)
		(pad "1" smd rect
			(at 0 0 90)
			(size 0.508 0.508)
			(layers "B.Cu" "B.Mask" "B.Paste")
			(net "SMB_DDR_GHJ_SCL_G_R")
		)
		(pad "2" smd rect
			(at 0 0.889 90)
			(size 0.508 0.508)
			(layers "B.Cu" "B.Mask" "B.Paste")
			(net "SMB_DDR_GHJ_SCL_G")
		)
		(zone
			(layer "B.Cu")
			(hatch none 0.5)
			(connect_pads
				(clearance 0)
			)
			(min_thickness 0.25)
			(keepout
				(tracks not_allowed)
				(vias allowed)
				(pads allowed)
				(copperpour not_allowed)
				(footprints allowed)
			)
			(placement
				(enabled no)
				(sheetname "")
			)
			(fill
				(thermal_gap 0.5)
				(thermal_bridge_width 0.5)
				(island_removal_mode 0)
			)
			(polygon
				(pts
					(xy 166.981124 -22.495764) (xy 166.981124 -23.003764) (xy 167.362124 -23.003764) (xy 167.362124 -22.495764)
				)
			)
		)
		(zone
			(layer "B.Cu")
			(hatch none 0.5)
			(connect_pads
				(clearance 0)
			)
			(min_thickness 0.25)
			(keepout
				(tracks allowed)
				(vias not_allowed)
				(pads allowed)
				(copperpour not_allowed)
				(footprints allowed)
			)
			(placement
				(enabled no)
				(sheetname "")
			)
			(fill
				(thermal_gap 0.5)
				(thermal_bridge_width 0.5)
				(island_removal_mode 0)
			)
			(polygon
				(pts
					(xy 167.362124 -22.495764) (xy 167.362124 -23.003764) (xy 166.981124 -23.003764) (xy 166.981124 -22.495764)
				)
			)
		)
	)
	(footprint ""
		(layer "B.Cu")
		(at 276.836886 -77.82814)
		(property "Reference" "C4P4"
			(at 0 0 0)
			(layer "B.SilkS")
			(hide yes)
			(effects
				(font
					(size 1.27 1.27)
				)
				(justify mirror)
			)
		)
		(property "Value" ""
			(at 0 0 0)
			(layer "B.Fab")
			(effects
				(font
					(size 1.27 1.27)
				)
				(justify mirror)
			)
		)
		(duplicate_pad_numbers_are_jumpers no)
		(fp_poly
			(pts
				(xy 0.7239 -0.2159) (xy -0.7239 -0.2159) (xy -0.7239 1.9939) (xy 0.7239 1.9939)
			)
			(stroke
				(width 0)
				(type default)
			)
			(fill no)
			(layer "B.CrtYd")
		)
		(fp_line
			(start -0.7239 -0.2159)
			(end 0.7239 -0.2159)
			(stroke
				(width 0.1)
				(type default)
			)
			(layer "B.Fab")
		)
		(fp_line
			(start -0.7239 1.9939)
			(end -0.7239 -0.2159)
			(stroke
				(width 0.1)
				(type default)
			)
			(layer "B.Fab")
		)
		(fp_line
			(start 0.7239 -0.2159)
			(end 0.7239 1.9939)
			(stroke
				(width 0.1)
				(type default)
			)
			(layer "B.Fab")
		)
		(fp_line
			(start 0.7239 1.9939)
			(end -0.7239 1.9939)
			(stroke
				(width 0.1)
				(type default)
			)
			(layer "B.Fab")
		)
		(pad "1" smd rect
			(at 0 0 180)
			(size 1.27 1.016)
			(layers "B.Cu" "B.Mask" "B.Paste")
			(net "PVCCMCP_CPU0")
		)
		(pad "2" smd rect
			(at 0 1.778 180)
			(size 1.27 1.016)
			(layers "B.Cu" "B.Mask" "B.Paste")
			(net "GND")
		)
		(zone
			(layer "B.Cu")
			(hatch none 0.5)
			(connect_pads
				(clearance 0)
			)
			(min_thickness 0.25)
			(keepout
				(tracks not_allowed)
				(vias allowed)
				(pads allowed)
				(copperpour not_allowed)
				(footprints allowed)
			)
			(placement
				(enabled no)
				(sheetname "")
			)
			(fill
				(thermal_gap 0.5)
				(thermal_bridge_width 0.5)
				(island_removal_mode 0)
			)
			(polygon
				(pts
					(xy 277.471886 -77.32014) (xy 276.201886 -77.32014) (xy 276.201886 -76.55814) (xy 277.471886 -76.55814)
				)
			)
		)
	)
	(footprint ""
		(layer "B.Cu")
		(at 111.983012 -29.94152 90)
		(property "Reference" "R7U2"
			(at 0 0 90)
			(layer "B.SilkS")
			(hide yes)
			(effects
				(font
					(size 1.27 1.27)
				)
				(justify mirror)
			)
		)
		(property "Value" ""
			(at 0 0 90)
			(layer "B.Fab")
			(effects
				(font
					(size 1.27 1.27)
				)
				(justify mirror)
			)
		)
		(duplicate_pad_numbers_are_jumpers no)
		(fp_poly
			(pts
				(xy 0.2794 -0.1016) (xy -0.2794 -0.1016) (xy -0.2794 0.9906) (xy 0.2794 0.9906)
			)
			(stroke
				(width 0)
				(type default)
			)
			(fill no)
			(layer "B.CrtYd")
		)
		(fp_line
			(start 0.2794 -0.1016)
			(end 0.2794 0.9906)
			(stroke
				(width 0.1)
				(type default)
			)
			(layer "B.Fab")
		)
		(fp_line
			(start -0.2794 -0.1016)
			(end 0.2794 -0.1016)
			(stroke
				(width 0.1)
				(type default)
			)
			(layer "B.Fab")
		)
		(fp_line
			(start 0.2794 0.9906)
			(end -0.2794 0.9906)
			(stroke
				(width 0.1)
				(type default)
			)
			(layer "B.Fab")
		)
		(fp_line
			(start -0.2794 0.9906)
			(end -0.2794 -0.1016)
			(stroke
				(width 0.1)
				(type default)
			)
			(layer "B.Fab")
		)
		(pad "1" smd rect
			(at 0 0 270)
			(size 0.508 0.508)
			(layers "B.Cu" "B.Mask" "B.Paste")
			(net "VSENSE_PVDDQ_GHJ_P")
		)
		(pad "2" smd rect
			(at 0 0.889 270)
			(size 0.508 0.508)
			(layers "B.Cu" "B.Mask" "B.Paste")
			(net "VSENSE_PVDDQ_GHJ_N")
		)
		(zone
			(layer "B.Cu")
			(hatch none 0.5)
			(connect_pads
				(clearance 0)
			)
			(min_thickness 0.25)
			(keepout
				(tracks allowed)
				(vias not_allowed)
				(pads allowed)
				(copperpour not_allowed)
				(footprints allowed)
			)
			(placement
				(enabled no)
				(sheetname "")
			)
			(fill
				(thermal_gap 0.5)
				(thermal_bridge_width 0.5)
				(island_removal_mode 0)
			)
			(polygon
				(pts
					(xy 112.237012 -30.19552) (xy 112.237012 -29.68752) (xy 112.618012 -29.68752) (xy 112.618012 -30.19552)
				)
			)
		)
		(zone
			(layer "B.Cu")
			(hatch none 0.5)
			(connect_pads
				(clearance 0)
			)
			(min_thickness 0.25)
			(keepout
				(tracks not_allowed)
				(vias allowed)
				(pads allowed)
				(copperpour not_allowed)
				(footprints allowed)
			)
			(placement
				(enabled no)
				(sheetname "")
			)
			(fill
				(thermal_gap 0.5)
				(thermal_bridge_width 0.5)
				(island_removal_mode 0)
			)
			(polygon
				(pts
					(xy 112.618012 -30.19552) (xy 112.618012 -29.68752) (xy 112.237012 -29.68752) (xy 112.237012 -30.19552)
				)
			)
		)
	)
)
